# S9S_MB_2U (Grand Teton) — schematic netlist excerpt (pin names and nets, part order shuffled) for the footprints in the layout excerpt that follows; sources: Cadence DE-HDL packaged netlist, KiCad conversion of 03242023_DA0F0TMBIJ0_F0T_Motherboard_J_brd_V01_OCP.brd

C1392  Q_CAP  47UF 4V 20% X6S  pkg C0805  page 78 : A = PVPP_HBM_CPU1 ; B = GND
C1261  Q_CAP  10UF 6.3V 20% X6S  pkg C0603  page 189 : A = P1V8_PCH_PLL_AUX ; B = GND
PR220  Q_RES  1 1% CHIP  pkg 0402LF  page 296 : A = PVCCD_HV_CPU1_VCC ; B = P3V3_AUX

(kicad_pcb
	(version 20260206)
	(generator "pcbnew")
	(generator_version "10.0")
	(general
		(thickness 1.6)
		(legacy_teardrops no)
	)
	(paper "A4")
	(title_block
		(title "03242023_DA0F0TMBIJ0_F0T_Motherboard_J_brd_V01_OCP.brd")
		(comment 1 "Grand Teton / footprints 6066-6068 of 6105")
	)
	(layers
		(0 "F.Cu" signal "TOP")
		(4 "In1.Cu" signal "GND")
		(6 "In2.Cu" signal "IN1")
		(8 "In3.Cu" signal "GND1")
		(10 "In4.Cu" signal "IN2")
		(12 "In5.Cu" signal "GND2")
		(14 "In6.Cu" signal "IN3")
		(16 "In7.Cu" signal "GND3")
		(18 "In8.Cu" signal "VCC")
		(20 "In9.Cu" signal "VCC1")
		(22 "In10.Cu" signal "GND4")
		(24 "In11.Cu" signal "IN4")
		(26 "In12.Cu" signal "GND5")
		(28 "In13.Cu" signal "IN5")
		(30 "In14.Cu" signal "GND6")
		(32 "In15.Cu" signal "IN6")
		(34 "In16.Cu" signal "GND7")
		(2 "B.Cu" signal "BOTTOM")
		(9 "F.Adhes" user "F.Adhesive")
		(11 "B.Adhes" user "B.Adhesive")
		(13 "F.Paste" user "Package Geometry/Pastemask Top")
		(15 "B.Paste" user "Package Geometry/Pastemask Bottom")
		(5 "F.SilkS" user "Ref Des/Silkscreen Top")
		(7 "B.SilkS" user "Ref Des/Silkscreen Bottom")
		(1 "F.Mask" user "Board Geometry/Soldermask Top")
		(3 "B.Mask" user "Board Geometry/Soldermask Bottom")
		(17 "Dwgs.User" user "User.Drawings")
		(19 "Cmts.User" user "User.Comments")
		(21 "Eco1.User" user "User.Eco1")
		(23 "Eco2.User" user "User.Eco2")
		(25 "Edge.Cuts" user "Board Geometry/Outline")
		(27 "Margin" user)
		(31 "F.CrtYd" user "Package Geometry/Place Bound Top")
		(29 "B.CrtYd" user "Package Geometry/Place Bound Bottom")
		(35 "F.Fab" user "Ref Des/Assembly Top")
		(33 "B.Fab" user "Ref Des/Assembly Bottom")
	)
	(footprint ""
		(layer "B.Cu")
		(at 143.793718 -337.86318)
		(property "Reference" "C1392"
			(at 0 0 0)
			(layer "B.SilkS")
			(hide yes)
			(effects
				(font
					(size 1.27 1.27)
				)
				(justify mirror)
			)
		)
		(property "Value" ""
			(at 0 0 0)
			(layer "B.Fab")
			(effects
				(font
					(size 1.27 1.27)
				)
				(justify mirror)
			)
		)
		(duplicate_pad_numbers_are_jumpers no)
		(fp_line
			(start -1.524 -0.762)
			(end -1.524 0.762)
			(stroke
				(width 0.1524)
				(type default)
			)
			(layer "B.SilkS")
		)
		(fp_line
			(start -1.524 0.762)
			(end 1.524 0.762)
			(stroke
				(width 0.1524)
				(type default)
			)
			(layer "B.SilkS")
		)
		(fp_line
			(start 1.524 -0.762)
			(end -1.524 -0.762)
			(stroke
				(width 0.1524)
				(type default)
			)
			(layer "B.SilkS")
		)
		(fp_line
			(start 1.524 0.762)
			(end 1.524 -0.762)
			(stroke
				(width 0.1524)
				(type default)
			)
			(layer "B.SilkS")
		)
		(fp_line
			(start -1.1049 -0.724916)
			(end 1.1049 -0.724916)
			(stroke
				(width 0.1)
				(type default)
			)
			(layer "B.Fab")
		)
		(fp_line
			(start -1.1049 0.724916)
			(end -1.1049 -0.724916)
			(stroke
				(width 0.1)
				(type default)
			)
			(layer "B.Fab")
		)
		(fp_line
			(start 1.1049 -0.724916)
			(end 1.1049 0.724916)
			(stroke
				(width 0.1)
				(type default)
			)
			(layer "B.Fab")
		)
		(fp_line
			(start 1.1049 0.724916)
			(end -1.1049 0.724916)
			(stroke
				(width 0.1)
				(type default)
			)
			(layer "B.Fab")
		)
		(pad "1" smd rect
			(at 0.889 0)
			(size 1.016 1.27)
			(layers "B.Cu" "B.Mask" "B.Paste")
			(net "PVPP_HBM_CPU1")
		)
		(pad "2" smd rect
			(at -0.889 0)
			(size 1.016 1.27)
			(layers "B.Cu" "B.Mask" "B.Paste")
			(net "GND")
		)
	)
	(footprint ""
		(layer "B.Cu")
		(at 348.770194 -54.496208 90)
		(property "Reference" "C1261"
			(at 0 0 90)
			(layer "B.SilkS")
			(hide yes)
			(effects
				(font
					(size 1.27 1.27)
				)
				(justify mirror)
			)
		)
		(property "Value" ""
			(at 0 0 90)
			(layer "B.Fab")
			(effects
				(font
					(size 1.27 1.27)
				)
				(justify mirror)
			)
		)
		(duplicate_pad_numbers_are_jumpers no)
		(fp_line
			(start 1.2954 -0.5842)
			(end -1.2954 -0.5842)
			(stroke
				(width 0.1524)
				(type default)
			)
			(layer "B.SilkS")
		)
		(fp_line
			(start 0 -0.5842)
			(end 0 0.5842)
			(stroke
				(width 0.1524)
				(type default)
			)
			(layer "B.SilkS")
		)
		(fp_line
			(start -1.2954 -0.5842)
			(end -1.2954 0.5842)
			(stroke
				(width 0.1524)
				(type default)
			)
			(layer "B.SilkS")
		)
		(fp_line
			(start 1.2954 0.5842)
			(end 1.2954 -0.5842)
			(stroke
				(width 0.1524)
				(type default)
			)
			(layer "B.SilkS")
		)
		(fp_line
			(start -1.2954 0.5842)
			(end 1.2954 0.5842)
			(stroke
				(width 0.1524)
				(type default)
			)
			(layer "B.SilkS")
		)
		(fp_line
			(start 0.8636 -0.4572)
			(end -0.8636 -0.4572)
			(stroke
				(width 0.1)
				(type default)
			)
			(layer "B.Fab")
		)
		(fp_line
			(start -0.8636 -0.4572)
			(end -0.8636 -0.4064)
			(stroke
				(width 0.1)
				(type default)
			)
			(layer "B.Fab")
		)
		(fp_line
			(start 1.1938 -0.4064)
			(end 0.8636 -0.4064)
			(stroke
				(width 0.1)
				(type default)
			)
			(layer "B.Fab")
		)
		(fp_line
			(start 0.8636 -0.4064)
			(end 0.8636 -0.4572)
			(stroke
				(width 0.1)
				(type default)
			)
			(layer "B.Fab")
		)
		(fp_line
			(start -0.8636 -0.4064)
			(end -1.1938 -0.4064)
			(stroke
				(width 0.1)
				(type default)
			)
			(layer "B.Fab")
		)
		(fp_line
			(start -1.1938 -0.4064)
			(end -1.1938 0.4064)
			(stroke
				(width 0.1)
				(type default)
			)
			(layer "B.Fab")
		)
		(fp_line
			(start 1.1938 0.4064)
			(end 1.1938 -0.4064)
			(stroke
				(width 0.1)
				(type default)
			)
			(layer "B.Fab")
		)
		(fp_line
			(start 0.8636 0.4064)
			(end 1.1938 0.4064)
			(stroke
				(width 0.1)
				(type default)
			)
			(layer "B.Fab")
		)
		(fp_line
			(start -0.8636 0.4064)
			(end -0.8636 0.4572)
			(stroke
				(width 0.1)
				(type default)
			)
			(layer "B.Fab")
		)
		(fp_line
			(start -1.1938 0.4064)
			(end -0.8636 0.4064)
			(stroke
				(width 0.1)
				(type default)
			)
			(layer "B.Fab")
		)
		(fp_line
			(start 0.8636 0.4572)
			(end 0.8636 0.4064)
			(stroke
				(width 0.1)
				(type default)
			)
			(layer "B.Fab")
		)
		(fp_line
			(start -0.8636 0.4572)
			(end 0.8636 0.4572)
			(stroke
				(width 0.1)
				(type default)
			)
			(layer "B.Fab")
		)
		(pad "1" smd rect
			(at 0.7366 0)
			(size 0.7112 0.8128)
			(layers "B.Cu" "B.Mask" "B.Paste")
			(net "P1V8_PCH_PLL_AUX")
		)
		(pad "2" smd rect
			(at -0.7366 0)
			(size 0.7112 0.8128)
			(layers "B.Cu" "B.Mask" "B.Paste")
			(net "GND")
		)
	)
	(footprint ""
		(layer "B.Cu")
		(at 31.396432 -169.5958 180)
		(property "Reference" "PR220"
			(at 0 0 0)
			(layer "B.SilkS")
			(hide yes)
			(effects
				(font
					(size 1.27 1.27)
				)
				(justify mirror)
			)
		)
		(property "Value" ""
			(at 0 0 0)
			(layer "B.Fab")
			(effects
				(font
					(size 1.27 1.27)
				)
				(justify mirror)
			)
		)
		(duplicate_pad_numbers_are_jumpers no)
		(fp_line
			(start 0.7874 0.4064)
			(end 0.7874 -0.4064)
			(stroke
				(width 0.1524)
				(type default)
			)
			(layer "B.SilkS")
		)
		(fp_line
			(start 0.7874 -0.4064)
			(end -0.7874 -0.4064)
			(stroke
				(width 0.1524)
				(type default)
			)
			(layer "B.SilkS")
		)
		(fp_line
			(start -0.7874 0.4064)
			(end 0.7874 0.4064)
			(stroke
				(width 0.1524)
				(type default)
			)
			(layer "B.SilkS")
		)
		(fp_line
			(start -0.7874 -0.4064)
			(end -0.7874 0.4064)
			(stroke
				(width 0.1524)
				(type default)
			)
			(layer "B.SilkS")
		)
		(fp_line
			(start 0.67945 0.3048)
			(end 0.67945 -0.305054)
			(stroke
				(width 0.1)
				(type default)
			)
			(layer "B.Fab")
		)
		(fp_line
			(start 0.67945 -0.305054)
			(end 0.12065 -0.305054)
			(stroke
				(width 0.1)
				(type default)
			)
			(layer "B.Fab")
		)
		(fp_line
			(start 0.12065 0.3048)
			(end 0.67945 0.3048)
			(stroke
				(width 0.1)
				(type default)
			)
			(layer "B.Fab")
		)
		(fp_line
			(start 0.12065 0.2794)
			(end 0.12065 0.3048)
			(stroke
				(width 0.1)
				(type default)
			)
			(layer "B.Fab")
		)
		(fp_line
			(start 0.12065 -0.2794)
			(end -0.12065 -0.2794)
			(stroke
				(width 0.1)
				(type default)
			)
			(layer "B.Fab")
		)
		(fp_line
			(start 0.12065 -0.305054)
			(end 0.12065 -0.2794)
			(stroke
				(width 0.1)
				(type default)
			)
			(layer "B.Fab")
		)
		(fp_line
			(start -0.120396 0.3048)
			(end -0.120396 0.2794)
			(stroke
				(width 0.1)
				(type default)
			)
			(layer "B.Fab")
		)
		(fp_line
			(start -0.120396 0.2794)
			(end 0.12065 0.2794)
			(stroke
				(width 0.1)
				(type default)
			)
			(layer "B.Fab")
		)
		(fp_line
			(start -0.12065 -0.2794)
			(end -0.12065 -0.3048)
			(stroke
				(width 0.1)
				(type default)
			)
			(layer "B.Fab")
		)
		(fp_line
			(start -0.12065 -0.3048)
			(end -0.67945 -0.3048)
			(stroke
				(width 0.1)
				(type default)
			)
			(layer "B.Fab")
		)
		(fp_line
			(start -0.67945 0.3048)
			(end -0.120396 0.3048)
			(stroke
				(width 0.1)
				(type default)
			)
			(layer "B.Fab")
		)
		(fp_line
			(start -0.67945 -0.3048)
			(end -0.67945 0.3048)
			(stroke
				(width 0.1)
				(type default)
			)
			(layer "B.Fab")
		)
		(pad "1" smd circle
			(at 0.40005 0)
			(size 0 0)
			(layers "B.Cu" "B.Mask" "B.Paste")
			(net "PVCCD_HV_CPU1_VCC")
		)
		(pad "2" smd circle
			(at -0.40005 0)
			(size 0 0)
			(layers "B.Cu" "B.Mask" "B.Paste")
			(net "P3V3_AUX")
		)
	)
)
